#ISCELL
  mstr_misc dns *
  *
#ISCELL
  pure_quanta quanta_title_block_c *
  *
#ISCELL
  logical_power universal_gnd *
  page279_i1
#CELL
  pure_quanta q_cap *
  page279_i10
#CELL
  pure_quanta q_res *
  page279_i11
#ISCELL
  logical_power universal_gnd *
  page279_i12
#CELL
  pure_quanta q_cap *
  page279_i13
#ISCELL
  logical_power vcc15 *
  page279_i14
#ISCELL
  logical_power universal_gnd *
  page279_i15
#CELL
  pure_quanta q_res *
  page279_i16
#ISCELL
  logical_power universal_gnd *
  page279_i17
#ISCELL
  standard offpage *
  page279_i18
#ISCELL
  standard offpage *
  page279_i19
#ISCELL
  logical_power universal_gnd *
  page279_i2
#CELL
  pure_quanta q_cap *
  page279_i20
#ISCELL
  standard offpage *
  page279_i21
#ISCELL
  standard offpage *
  page279_i22
#ISCELL
  logical_power universal_gnd *
  page279_i23
#CELL
  pure_quanta q_cap *
  page279_i24
#CELL
  pure_quanta q_res *
  page279_i25
#CELL
  pure_quanta q_cap *
  page279_i26
#ISCELL
  logical_power universal_gnd *
  page279_i27
#ISCELL
  logical_power vcc15 *
  page279_i28
#CELL
  pure_quanta isl99390frztr5935 *
  page279_i29
#CELL
  pure_quanta q_res *
  page279_i3
#ISCELL
  logical_power universal_gnd *
  page279_i30
#CELL
  pure_quanta q_res *
  page279_i31
#CELL
  pure_quanta q_cap *
  page279_i32
#CELL
  pure_quanta q_cap *
  page279_i33
#CELL
  pure_quanta q_res *
  page279_i34
#ISCELL
  logical_power universal_gnd *
  page279_i35
#CELL
  pure_quanta q_cap *
  page279_i36
#CELL
  pure_quanta q_cap *
  page279_i37
#CELL
  pure_quanta isl99390frztr5935 *
  page279_i38
#ISCELL
  logical_power universal_gnd *
  page279_i39
#ISCELL
  standard offpage *
  page279_i4
#CELL
  pure_quanta q_cap *
  page279_i40
#CELL
  pure_quanta q_cap *
  page279_i41
#CELL
  pure_quanta q_res *
  page279_i42
#CELL
  pure_quanta q_cap *
  page279_i43
#CELL
  pure_quanta q_cap *
  page279_i44
#CELL
  pure_quanta q_cap *
  page279_i45
#CELL
  pure_quanta q_inductor *
  page279_i46
#ISCELL
  logical_power universal_gnd *
  page279_i47
#ISCELL
  logical_power vcc15 *
  page279_i48
#CELL
  pure_quanta q_res *
  page279_i49
#ISCELL
  standard offpage *
  page279_i5
#CELL
  pure_quanta q_res *
  page279_i50
#CELL
  pure_quanta q_cap *
  page279_i51
#CELL
  pure_quanta q_cap *
  page279_i52
#CELL
  pure_quanta q_cap *
  page279_i53
#CELL
  pure_quanta q_inductor *
  page279_i54
#CELL
  pure_quanta q_cap *
  page279_i55
#ISCELL
  logical_power universal_gnd *
  page279_i56
#ISCELL
  logical_power vcc15 *
  page279_i57
#ISCELL
  logical_power vcc15 *
  page279_i58
#CELL
  pure_quanta q_capp *
  page279_i59
#CELL
  pure_quanta q_cap *
  page279_i6
#CELL
  pure_quanta q_capp *
  page279_i60
#CELL
  pure_quanta q_capp *
  page279_i61
#CELL
  pure_quanta q_capp *
  page279_i62
#CELL
  pure_quanta q_cap *
  page279_i63
#ISCELL
  logical_power universal_gnd *
  page279_i64
#CELL
  pure_quanta q_cap *
  page279_i65
#ISCELL
  logical_power vcc15 *
  page279_i66
#ISCELL
  logical_power gnd *
  page279_i67
#CELL
  pure_quanta q_cap *
  page279_i68
#CELL
  pure_quanta q_capp *
  page279_i69
#ISCELL
  standard offpage *
  page279_i7
#CELL
  pure_quanta q_capp *
  page279_i70
#CELL
  pure_quanta q_capp *
  page279_i71
#ISCELL
  logical_power universal_gnd *
  page279_i72
#ISCELL
  logical_power vcc15 *
  page279_i73
#ISCELL
  logical_power universal_gnd *
  page279_i74
#ISCELL
  logical_power vcc15 *
  page279_i75
#ISCELL
  logical_power universal_gnd *
  page279_i76
#ISCELL
  logical_power vcc15 *
  page279_i77
#CELL
  pure_quanta q_inductor *
  page279_i78
#ISCELL
  logical_power vcc15 *
  page279_i79
#ISCELL
  standard offpage *
  page279_i8
#ISCELL
  logical_power universal_gnd *
  page279_i9
